(kicad_pcb
	(version 20260206)
	(generator "pcbnew")
	(generator_version "10.0")
	(general
		(thickness 1.6)
		(legacy_teardrops no)
	)
	(paper "A4")
	(title_block
		(title "01162023_DA0F0TEBIF0_F0T_Expander_BD_F_brd_V02_OCP.brd")
		(comment 1 "Grand Teton / footprints 8363-8371 of 9728")
	)
	(layers
		(0 "F.Cu" signal "TOP")
		(4 "In1.Cu" signal "GND")
		(6 "In2.Cu" signal "VCC")
		(8 "In3.Cu" signal "VCC1")
		(10 "In4.Cu" signal "GND1")
		(12 "In5.Cu" signal "IN1")
		(14 "In6.Cu" signal "GND2")
		(16 "In7.Cu" signal "IN2")
		(18 "In8.Cu" signal "GND3")
		(20 "In9.Cu" signal "IN3")
		(22 "In10.Cu" signal "GND4")
		(24 "In11.Cu" signal "IN4")
		(26 "In12.Cu" signal "GND5")
		(28 "In13.Cu" signal "IN5")
		(30 "In14.Cu" signal "GND6")
		(32 "In15.Cu" signal "IN6")
		(34 "In16.Cu" signal "GND7")
		(2 "B.Cu" signal "BOTTOM")
		(9 "F.Adhes" user "F.Adhesive")
		(11 "B.Adhes" user "B.Adhesive")
		(13 "F.Paste" user "Package Geometry/Pastemask Top")
		(15 "B.Paste" user "Package Geometry/Pastemask Bottom")
		(5 "F.SilkS" user "Ref Des/Silkscreen Top")
		(7 "B.SilkS" user "Ref Des/Silkscreen Bottom")
		(1 "F.Mask" user "Board Geometry/Soldermask Top")
		(3 "B.Mask" user "Board Geometry/Soldermask Bottom")
		(17 "Dwgs.User" user "User.Drawings")
		(19 "Cmts.User" user "User.Comments")
		(21 "Eco1.User" user "User.Eco1")
		(23 "Eco2.User" user "User.Eco2")
		(25 "Edge.Cuts" user "Board Geometry/Outline")
		(27 "Margin" user)
		(31 "F.CrtYd" user "Package Geometry/Place Bound Top")
		(29 "B.CrtYd" user "Package Geometry/Place Bound Bottom")
		(35 "F.Fab" user "Ref Des/Assembly Top")
		(33 "B.Fab" user "Ref Des/Assembly Bottom")
	)
	(footprint ""
		(layer "B.Cu")
		(at 388.949946 -288.774886 -90)
		(property "Reference" "R3491"
			(at 0 0 90)
			(layer "B.SilkS")
			(hide yes)
			(effects
				(font
					(size 1.27 1.27)
				)
				(justify mirror)
			)
		)
		(property "Value" ""
			(at 0 0 90)
			(layer "B.Fab")
			(effects
				(font
					(size 1.27 1.27)
				)
				(justify mirror)
			)
		)
		(duplicate_pad_numbers_are_jumpers no)
		(fp_line
			(start -0.7874 0.4064)
			(end 0.7874 0.4064)
			(stroke
				(width 0.1524)
				(type default)
			)
			(layer "B.SilkS")
		)
		(fp_line
			(start 0.7874 0.4064)
			(end 0.7874 -0.4064)
			(stroke
				(width 0.1524)
				(type default)
			)
			(layer "B.SilkS")
		)
		(fp_line
			(start -0.7874 -0.4064)
			(end -0.7874 0.4064)
			(stroke
				(width 0.1524)
				(type default)
			)
			(layer "B.SilkS")
		)
		(fp_line
			(start 0.7874 -0.4064)
			(end -0.7874 -0.4064)
			(stroke
				(width 0.1524)
				(type default)
			)
			(layer "B.SilkS")
		)
		(fp_line
			(start -0.67945 0.3048)
			(end -0.120396 0.3048)
			(stroke
				(width 0.1)
				(type default)
			)
			(layer "B.Fab")
		)
		(fp_line
			(start -0.120396 0.3048)
			(end -0.120396 0.2794)
			(stroke
				(width 0.1)
				(type default)
			)
			(layer "B.Fab")
		)
		(fp_line
			(start 0.12065 0.3048)
			(end 0.67945 0.3048)
			(stroke
				(width 0.1)
				(type default)
			)
			(layer "B.Fab")
		)
		(fp_line
			(start 0.67945 0.3048)
			(end 0.67945 -0.305054)
			(stroke
				(width 0.1)
				(type default)
			)
			(layer "B.Fab")
		)
		(fp_line
			(start -0.120396 0.2794)
			(end 0.12065 0.2794)
			(stroke
				(width 0.1)
				(type default)
			)
			(layer "B.Fab")
		)
		(fp_line
			(start 0.12065 0.2794)
			(end 0.12065 0.3048)
			(stroke
				(width 0.1)
				(type default)
			)
			(layer "B.Fab")
		)
		(fp_line
			(start -0.12065 -0.2794)
			(end -0.12065 -0.3048)
			(stroke
				(width 0.1)
				(type default)
			)
			(layer "B.Fab")
		)
		(fp_line
			(start 0.12065 -0.2794)
			(end -0.12065 -0.2794)
			(stroke
				(width 0.1)
				(type default)
			)
			(layer "B.Fab")
		)
		(fp_line
			(start -0.67945 -0.3048)
			(end -0.67945 0.3048)
			(stroke
				(width 0.1)
				(type default)
			)
			(layer "B.Fab")
		)
		(fp_line
			(start -0.12065 -0.3048)
			(end -0.67945 -0.3048)
			(stroke
				(width 0.1)
				(type default)
			)
			(layer "B.Fab")
		)
		(fp_line
			(start 0.12065 -0.305054)
			(end 0.12065 -0.2794)
			(stroke
				(width 0.1)
				(type default)
			)
			(layer "B.Fab")
		)
		(fp_line
			(start 0.67945 -0.305054)
			(end 0.12065 -0.305054)
			(stroke
				(width 0.1)
				(type default)
			)
			(layer "B.Fab")
		)
		(pad "1" smd circle
			(at 0.40005 0 90)
			(size 0 0)
			(layers "B.Cu" "B.Mask" "B.Paste")
			(net "SPI_PEX3_CS_R_N")
		)
		(pad "2" smd circle
			(at -0.40005 0 90)
			(size 0 0)
			(layers "B.Cu" "B.Mask" "B.Paste")
			(net "SPI_PEX3_CS_N")
		)
	)
	(footprint ""
		(layer "B.Cu")
		(at 225.539046 -153.127202 -90)
		(property "Reference" "C2799"
			(at 0 0 90)
			(layer "B.SilkS")
			(hide yes)
			(effects
				(font
					(size 1.27 1.27)
				)
				(justify mirror)
			)
		)
		(property "Value" ""
			(at 0 0 90)
			(layer "B.Fab")
			(effects
				(font
					(size 1.27 1.27)
				)
				(justify mirror)
			)
		)
		(duplicate_pad_numbers_are_jumpers no)
		(fp_line
			(start -1.2954 0.5842)
			(end 1.2954 0.5842)
			(stroke
				(width 0.1524)
				(type default)
			)
			(layer "B.SilkS")
		)
		(fp_line
			(start 1.2954 0.5842)
			(end 1.2954 -0.5842)
			(stroke
				(width 0.1524)
				(type default)
			)
			(layer "B.SilkS")
		)
		(fp_line
			(start -1.2954 -0.5842)
			(end -1.2954 0.5842)
			(stroke
				(width 0.1524)
				(type default)
			)
			(layer "B.SilkS")
		)
		(fp_line
			(start 1.2954 -0.5842)
			(end -1.2954 -0.5842)
			(stroke
				(width 0.1524)
				(type default)
			)
			(layer "B.SilkS")
		)
		(fp_line
			(start -0.8636 0.4572)
			(end 0.8636 0.4572)
			(stroke
				(width 0.1)
				(type default)
			)
			(layer "B.Fab")
		)
		(fp_line
			(start 0.8636 0.4572)
			(end 0.8636 0.4064)
			(stroke
				(width 0.1)
				(type default)
			)
			(layer "B.Fab")
		)
		(fp_line
			(start -1.1938 0.4064)
			(end -0.8636 0.4064)
			(stroke
				(width 0.1)
				(type default)
			)
			(layer "B.Fab")
		)
		(fp_line
			(start -0.8636 0.4064)
			(end -0.8636 0.4572)
			(stroke
				(width 0.1)
				(type default)
			)
			(layer "B.Fab")
		)
		(fp_line
			(start 0.8636 0.4064)
			(end 1.1938 0.4064)
			(stroke
				(width 0.1)
				(type default)
			)
			(layer "B.Fab")
		)
		(fp_line
			(start 1.1938 0.4064)
			(end 1.1938 -0.4064)
			(stroke
				(width 0.1)
				(type default)
			)
			(layer "B.Fab")
		)
		(fp_line
			(start -1.1938 -0.4064)
			(end -1.1938 0.4064)
			(stroke
				(width 0.1)
				(type default)
			)
			(layer "B.Fab")
		)
		(fp_line
			(start -0.8636 -0.4064)
			(end -1.1938 -0.4064)
			(stroke
				(width 0.1)
				(type default)
			)
			(layer "B.Fab")
		)
		(fp_line
			(start 0.8636 -0.4064)
			(end 0.8636 -0.4572)
			(stroke
				(width 0.1)
				(type default)
			)
			(layer "B.Fab")
		)
		(fp_line
			(start 1.1938 -0.4064)
			(end 0.8636 -0.4064)
			(stroke
				(width 0.1)
				(type default)
			)
			(layer "B.Fab")
		)
		(fp_line
			(start -0.8636 -0.4572)
			(end -0.8636 -0.4064)
			(stroke
				(width 0.1)
				(type default)
			)
			(layer "B.Fab")
		)
		(fp_line
			(start 0.8636 -0.4572)
			(end -0.8636 -0.4572)
			(stroke
				(width 0.1)
				(type default)
			)
			(layer "B.Fab")
		)
		(pad "1" smd rect
			(at 0.7366 0 180)
			(size 0.7112 0.8128)
			(layers "B.Cu" "B.Mask" "B.Paste")
			(net "P3V3_CLK_GEN_VDDMXCK_CK440_PEX")
		)
		(pad "2" smd rect
			(at -0.7366 0 180)
			(size 0.7112 0.8128)
			(layers "B.Cu" "B.Mask" "B.Paste")
			(net "GND")
		)
	)
	(footprint ""
		(layer "B.Cu")
		(at 279.974802 -295.3766 90)
		(property "Reference" "C3388"
			(at 0 0 90)
			(layer "B.SilkS")
			(hide yes)
			(effects
				(font
					(size 1.27 1.27)
				)
				(justify mirror)
			)
		)
		(property "Value" ""
			(at 0 0 90)
			(layer "B.Fab")
			(effects
				(font
					(size 1.27 1.27)
				)
				(justify mirror)
			)
		)
		(duplicate_pad_numbers_are_jumpers no)
		(fp_line
			(start 0.299974 -0.150114)
			(end -0.299974 -0.150114)
			(stroke
				(width 0.1)
				(type default)
			)
			(layer "B.Fab")
		)
		(fp_line
			(start -0.299974 -0.150114)
			(end -0.299974 0.150114)
			(stroke
				(width 0.1)
				(type default)
			)
			(layer "B.Fab")
		)
		(fp_line
			(start 0.299974 0.150114)
			(end 0.299974 -0.150114)
			(stroke
				(width 0.1)
				(type default)
			)
			(layer "B.Fab")
		)
		(fp_line
			(start -0.299974 0.150114)
			(end 0.299974 0.150114)
			(stroke
				(width 0.1)
				(type default)
			)
			(layer "B.Fab")
		)
		(pad "1" smd rect
			(at 0.2667 0 270)
			(size 0.3048 0.381)
			(layers "B.Cu" "B.Mask" "B.Paste")
			(net "PCEPLL3_VDDA18_PEX2")
		)
		(pad "2" smd rect
			(at -0.2667 0 270)
			(size 0.3048 0.381)
			(layers "B.Cu" "B.Mask" "B.Paste")
			(net "GND")
		)
	)
	(footprint ""
		(layer "B.Cu")
		(at 388.35711 -291.72662 180)
		(property "Reference" "R3489"
			(at 0 0 0)
			(layer "B.SilkS")
			(hide yes)
			(effects
				(font
					(size 1.27 1.27)
				)
				(justify mirror)
			)
		)
		(property "Value" ""
			(at 0 0 0)
			(layer "B.Fab")
			(effects
				(font
					(size 1.27 1.27)
				)
				(justify mirror)
			)
		)
		(duplicate_pad_numbers_are_jumpers no)
		(fp_line
			(start 0.7874 0.4064)
			(end 0.7874 -0.4064)
			(stroke
				(width 0.1524)
				(type default)
			)
			(layer "B.SilkS")
		)
		(fp_line
			(start 0.7874 -0.4064)
			(end -0.7874 -0.4064)
			(stroke
				(width 0.1524)
				(type default)
			)
			(layer "B.SilkS")
		)
		(fp_line
			(start -0.7874 0.4064)
			(end 0.7874 0.4064)
			(stroke
				(width 0.1524)
				(type default)
			)
			(layer "B.SilkS")
		)
		(fp_line
			(start -0.7874 -0.4064)
			(end -0.7874 0.4064)
			(stroke
				(width 0.1524)
				(type default)
			)
			(layer "B.SilkS")
		)
		(fp_line
			(start 0.67945 0.3048)
			(end 0.67945 -0.305054)
			(stroke
				(width 0.1)
				(type default)
			)
			(layer "B.Fab")
		)
		(fp_line
			(start 0.67945 -0.305054)
			(end 0.12065 -0.305054)
			(stroke
				(width 0.1)
				(type default)
			)
			(layer "B.Fab")
		)
		(fp_line
			(start 0.12065 0.3048)
			(end 0.67945 0.3048)
			(stroke
				(width 0.1)
				(type default)
			)
			(layer "B.Fab")
		)
		(fp_line
			(start 0.12065 0.2794)
			(end 0.12065 0.3048)
			(stroke
				(width 0.1)
				(type default)
			)
			(layer "B.Fab")
		)
		(fp_line
			(start 0.12065 -0.2794)
			(end -0.12065 -0.2794)
			(stroke
				(width 0.1)
				(type default)
			)
			(layer "B.Fab")
		)
		(fp_line
			(start 0.12065 -0.305054)
			(end 0.12065 -0.2794)
			(stroke
				(width 0.1)
				(type default)
			)
			(layer "B.Fab")
		)
		(fp_line
			(start -0.120396 0.3048)
			(end -0.120396 0.2794)
			(stroke
				(width 0.1)
				(type default)
			)
			(layer "B.Fab")
		)
		(fp_line
			(start -0.120396 0.2794)
			(end 0.12065 0.2794)
			(stroke
				(width 0.1)
				(type default)
			)
			(layer "B.Fab")
		)
		(fp_line
			(start -0.12065 -0.2794)
			(end -0.12065 -0.3048)
			(stroke
				(width 0.1)
				(type default)
			)
			(layer "B.Fab")
		)
		(fp_line
			(start -0.12065 -0.3048)
			(end -0.67945 -0.3048)
			(stroke
				(width 0.1)
				(type default)
			)
			(layer "B.Fab")
		)
		(fp_line
			(start -0.67945 0.3048)
			(end -0.120396 0.3048)
			(stroke
				(width 0.1)
				(type default)
			)
			(layer "B.Fab")
		)
		(fp_line
			(start -0.67945 -0.3048)
			(end -0.67945 0.3048)
			(stroke
				(width 0.1)
				(type default)
			)
			(layer "B.Fab")
		)
		(pad "1" smd circle
			(at 0.40005 0)
			(size 0 0)
			(layers "B.Cu" "B.Mask" "B.Paste")
			(net "SPI_PEX3_CLK_R")
		)
		(pad "2" smd circle
			(at -0.40005 0)
			(size 0 0)
			(layers "B.Cu" "B.Mask" "B.Paste")
			(net "SPI_PEX3_CLK")
		)
	)
	(footprint ""
		(layer "B.Cu")
		(at 333.073756 -327.942194 180)
		(property "Reference" "PJ22"
			(at 0 0 0)
			(layer "B.SilkS")
			(hide yes)
			(effects
				(font
					(size 1.27 1.27)
				)
				(justify mirror)
			)
		)
		(property "Value" ""
			(at 0 0 0)
			(layer "B.Fab")
			(effects
				(font
					(size 1.27 1.27)
				)
				(justify mirror)
			)
		)
		(duplicate_pad_numbers_are_jumpers no)
		(pad "1" smd circle
			(at 0.40005 0 270)
			(size 0 0)
			(layers "B.Cu" "B.Mask" "B.Paste")
			(net "VSENSE_P0V8_PEX2_SKT_VSEN")
		)
		(pad "2" smd rect
			(at -0.40005 0 180)
			(size 0.4572 0.508)
			(layers "B.Cu" "B.Mask" "B.Paste")
			(net "SH_P0V8_PEX2_VSEN2_L")
		)
		(zone
			(layer "B.Cu")
			(hatch none 0.5)
			(connect_pads
				(clearance 0)
			)
			(min_thickness 0.25)
			(keepout
				(tracks allowed)
				(vias not_allowed)
				(pads allowed)
				(copperpour not_allowed)
				(footprints allowed)
			)
			(placement
				(enabled no)
				(sheetname "")
			)
			(fill
				(thermal_gap 0.5)
				(thermal_bridge_width 0.5)
				(island_removal_mode 0)
			)
			(polygon
				(pts
					(xy 333.759556 -328.246994) (xy 333.759556 -327.637394) (xy 332.387956 -327.637394) (xy 332.387956 -328.246994)
				)
			)
		)
	)
	(footprint ""
		(layer "B.Cu")
		(at 299.449744 -292.099746 90)
		(property "Reference" "C1706"
			(at 0 0 90)
			(layer "B.SilkS")
			(hide yes)
			(effects
				(font
					(size 1.27 1.27)
				)
				(justify mirror)
			)
		)
		(property "Value" ""
			(at 0 0 90)
			(layer "B.Fab")
			(effects
				(font
					(size 1.27 1.27)
				)
				(justify mirror)
			)
		)
		(duplicate_pad_numbers_are_jumpers no)
		(fp_line
			(start 0.299974 -0.150114)
			(end -0.299974 -0.150114)
			(stroke
				(width 0.1)
				(type default)
			)
			(layer "B.Fab")
		)
		(fp_line
			(start -0.299974 -0.150114)
			(end -0.299974 0.150114)
			(stroke
				(width 0.1)
				(type default)
			)
			(layer "B.Fab")
		)
		(fp_line
			(start 0.299974 0.150114)
			(end 0.299974 -0.150114)
			(stroke
				(width 0.1)
				(type default)
			)
			(layer "B.Fab")
		)
		(fp_line
			(start -0.299974 0.150114)
			(end 0.299974 0.150114)
			(stroke
				(width 0.1)
				(type default)
			)
			(layer "B.Fab")
		)
		(pad "1" smd rect
			(at 0.2667 0 270)
			(size 0.3048 0.381)
			(layers "B.Cu" "B.Mask" "B.Paste")
			(net "P0V8_SERDES_VDDA_PEX2")
		)
		(pad "2" smd rect
			(at -0.2667 0 270)
			(size 0.3048 0.381)
			(layers "B.Cu" "B.Mask" "B.Paste")
			(net "GND")
		)
	)
	(footprint ""
		(layer "B.Cu")
		(at 72.949816 -297.79976 180)
		(property "Reference" "C2947"
			(at 0 0 0)
			(layer "B.SilkS")
			(hide yes)
			(effects
				(font
					(size 1.27 1.27)
				)
				(justify mirror)
			)
		)
		(property "Value" ""
			(at 0 0 0)
			(layer "B.Fab")
			(effects
				(font
					(size 1.27 1.27)
				)
				(justify mirror)
			)
		)
		(duplicate_pad_numbers_are_jumpers no)
		(fp_line
			(start 0.299974 0.150114)
			(end 0.299974 -0.150114)
			(stroke
				(width 0.1)
				(type default)
			)
			(layer "B.Fab")
		)
		(fp_line
			(start 0.299974 -0.150114)
			(end -0.299974 -0.150114)
			(stroke
				(width 0.1)
				(type default)
			)
			(layer "B.Fab")
		)
		(fp_line
			(start -0.299974 0.150114)
			(end 0.299974 0.150114)
			(stroke
				(width 0.1)
				(type default)
			)
			(layer "B.Fab")
		)
		(fp_line
			(start -0.299974 -0.150114)
			(end -0.299974 0.150114)
			(stroke
				(width 0.1)
				(type default)
			)
			(layer "B.Fab")
		)
		(pad "1" smd rect
			(at 0.2667 0)
			(size 0.3048 0.381)
			(layers "B.Cu" "B.Mask" "B.Paste")
			(net "P1V25_SERDES_VDDPLL_PEX0")
		)
		(pad "2" smd rect
			(at -0.2667 0)
			(size 0.3048 0.381)
			(layers "B.Cu" "B.Mask" "B.Paste")
			(net "GND")
		)
	)
	(footprint ""
		(layer "B.Cu")
		(at 69.149976 -296.37482 180)
		(property "Reference" "C1162"
			(at 0 0 0)
			(layer "B.SilkS")
			(hide yes)
			(effects
				(font
					(size 1.27 1.27)
				)
				(justify mirror)
			)
		)
		(property "Value" ""
			(at 0 0 0)
			(layer "B.Fab")
			(effects
				(font
					(size 1.27 1.27)
				)
				(justify mirror)
			)
		)
		(duplicate_pad_numbers_are_jumpers no)
		(fp_line
			(start 0.299974 0.150114)
			(end 0.299974 -0.150114)
			(stroke
				(width 0.1)
				(type default)
			)
			(layer "B.Fab")
		)
		(fp_line
			(start 0.299974 -0.150114)
			(end -0.299974 -0.150114)
			(stroke
				(width 0.1)
				(type default)
			)
			(layer "B.Fab")
		)
		(fp_line
			(start -0.299974 0.150114)
			(end 0.299974 0.150114)
			(stroke
				(width 0.1)
				(type default)
			)
			(layer "B.Fab")
		)
		(fp_line
			(start -0.299974 -0.150114)
			(end -0.299974 0.150114)
			(stroke
				(width 0.1)
				(type default)
			)
			(layer "B.Fab")
		)
		(pad "1" smd rect
			(at 0.2667 0)
			(size 0.3048 0.381)
			(layers "B.Cu" "B.Mask" "B.Paste")
			(net "P0V8_SERDES_VDDA_PEX0")
		)
		(pad "2" smd rect
			(at -0.2667 0)
			(size 0.3048 0.381)
			(layers "B.Cu" "B.Mask" "B.Paste")
			(net "GND")
		)
	)
	(footprint ""
		(layer "B.Cu")
		(at 40.119046 -294.8051 180)
		(property "Reference" "R3435"
			(at 0 0 0)
			(layer "B.SilkS")
			(hide yes)
			(effects
				(font
					(size 1.27 1.27)
				)
				(justify mirror)
			)
		)
		(property "Value" ""
			(at 0 0 0)
			(layer "B.Fab")
			(effects
				(font
					(size 1.27 1.27)
				)
				(justify mirror)
			)
		)
		(duplicate_pad_numbers_are_jumpers no)
		(fp_line
			(start 0.7874 0.4064)
			(end 0.7874 -0.4064)
			(stroke
				(width 0.1524)
				(type default)
			)
			(layer "B.SilkS")
		)
		(fp_line
			(start 0.7874 -0.4064)
			(end -0.7874 -0.4064)
			(stroke
				(width 0.1524)
				(type default)
			)
			(layer "B.SilkS")
		)
		(fp_line
			(start -0.7874 0.4064)
			(end 0.7874 0.4064)
			(stroke
				(width 0.1524)
				(type default)
			)
			(layer "B.SilkS")
		)
		(fp_line
			(start -0.7874 -0.4064)
			(end -0.7874 0.4064)
			(stroke
				(width 0.1524)
				(type default)
			)
			(layer "B.SilkS")
		)
		(fp_line
			(start 0.67945 0.3048)
			(end 0.67945 -0.305054)
			(stroke
				(width 0.1)
				(type default)
			)
			(layer "B.Fab")
		)
		(fp_line
			(start 0.67945 -0.305054)
			(end 0.12065 -0.305054)
			(stroke
				(width 0.1)
				(type default)
			)
			(layer "B.Fab")
		)
		(fp_line
			(start 0.12065 0.3048)
			(end 0.67945 0.3048)
			(stroke
				(width 0.1)
				(type default)
			)
			(layer "B.Fab")
		)
		(fp_line
			(start 0.12065 0.2794)
			(end 0.12065 0.3048)
			(stroke
				(width 0.1)
				(type default)
			)
			(layer "B.Fab")
		)
		(fp_line
			(start 0.12065 -0.2794)
			(end -0.12065 -0.2794)
			(stroke
				(width 0.1)
				(type default)
			)
			(layer "B.Fab")
		)
		(fp_line
			(start 0.12065 -0.305054)
			(end 0.12065 -0.2794)
			(stroke
				(width 0.1)
				(type default)
			)
			(layer "B.Fab")
		)
		(fp_line
			(start -0.120396 0.3048)
			(end -0.120396 0.2794)
			(stroke
				(width 0.1)
				(type default)
			)
			(layer "B.Fab")
		)
		(fp_line
			(start -0.120396 0.2794)
			(end 0.12065 0.2794)
			(stroke
				(width 0.1)
				(type default)
			)
			(layer "B.Fab")
		)
		(fp_line
			(start -0.12065 -0.2794)
			(end -0.12065 -0.3048)
			(stroke
				(width 0.1)
				(type default)
			)
			(layer "B.Fab")
		)
		(fp_line
			(start -0.12065 -0.3048)
			(end -0.67945 -0.3048)
			(stroke
				(width 0.1)
				(type default)
			)
			(layer "B.Fab")
		)
		(fp_line
			(start -0.67945 0.3048)
			(end -0.120396 0.3048)
			(stroke
				(width 0.1)
				(type default)
			)
			(layer "B.Fab")
		)
		(fp_line
			(start -0.67945 -0.3048)
			(end -0.67945 0.3048)
			(stroke
				(width 0.1)
				(type default)
			)
			(layer "B.Fab")
		)
		(pad "1" smd circle
			(at 0.40005 0)
			(size 0 0)
			(layers "B.Cu" "B.Mask" "B.Paste")
			(net "SPI_PEX0_SDIO2_R")
		)
		(pad "2" smd circle
			(at -0.40005 0)
			(size 0 0)
			(layers "B.Cu" "B.Mask" "B.Paste")
			(net "SPI_PEX0_SDIO2")
		)
	)
)
